(kicad_pcb
	(version 20260206)
	(generator "pcbnew")
	(generator_version "10.0")
	(general
		(thickness 1.6)
		(legacy_teardrops no)
	)
	(paper "A4")
	(title_block
		(title "Bryce Canyon_IOM_M2_16342-2_OCP.brd")
		(comment 1 "Bryce Canyon / footprints 696-696 of 1146")
	)
	(layers
		(0 "F.Cu" signal "TOP")
		(4 "In1.Cu" signal "L2GND")
		(6 "In2.Cu" signal "L3")
		(8 "In3.Cu" signal "L4VCC")
		(10 "In4.Cu" signal "L5VCC")
		(12 "In5.Cu" signal "L6")
		(14 "In6.Cu" signal "L7GND")
		(2 "B.Cu" signal "BOTTOM")
		(9 "F.Adhes" user "F.Adhesive")
		(11 "B.Adhes" user "B.Adhesive")
		(13 "F.Paste" user "Package Geometry/Pastemask Top")
		(15 "B.Paste" user "Package Geometry/Pastemask Bottom")
		(5 "F.SilkS" user "Ref Des/Silkscreen Top")
		(7 "B.SilkS" user "Ref Des/Silkscreen Bottom")
		(1 "F.Mask" user "Board Geometry/Soldermask Top")
		(3 "B.Mask" user "Board Geometry/Soldermask Bottom")
		(17 "Dwgs.User" user "User.Drawings")
		(19 "Cmts.User" user "User.Comments")
		(21 "Eco1.User" user "User.Eco1")
		(23 "Eco2.User" user "User.Eco2")
		(25 "Edge.Cuts" user "Board Geometry/Outline")
		(27 "Margin" user)
		(31 "F.CrtYd" user "Package Geometry/Place Bound Top")
		(29 "B.CrtYd" user "Package Geometry/Place Bound Bottom")
		(35 "F.Fab" user "Ref Des/Assembly Top")
		(33 "B.Fab" user "Ref Des/Assembly Bottom")
	)
	(footprint ""
		(layer "F.Cu")
		(at 204.399896 -129.599944)
		(property "Reference" "M1"
			(at 0 0 0)
			(layer "F.SilkS")
			(hide yes)
			(effects
				(font
					(size 1.27 1.27)
				)
			)
		)
		(property "Value" "SKT-MINI75P-11-GP"
			(at 12.6619 2.2733 0)
			(unlocked yes)
			(layer "F.Fab")
			(hide yes)
			(effects
				(font
					(size 1.016 1.016)
					(thickness 0.1524)
				)
			)
		)
		(property "Device Type" "MDT580M01001"
			(at 12.6619 0.7493 0)
			(unlocked yes)
			(layer "F.Fab")
			(hide yes)
			(effects
				(font
					(size 1.016 1.016)
					(thickness 0.1524)
				)
			)
		)
		(duplicate_pad_numbers_are_jumpers no)
		(fp_line
			(start -11.2522 -6.2992)
			(end 11.2522 -6.2992)
			(stroke
				(width 0.1524)
				(type default)
			)
			(layer "F.SilkS")
		)
		(fp_line
			(start -11.2522 3.302)
			(end -11.2522 -6.2992)
			(stroke
				(width 0.1524)
				(type default)
			)
			(layer "F.SilkS")
		)
		(fp_line
			(start -9.525 -6.3881)
			(end -9.017 -6.3881)
			(stroke
				(width 0.3302)
				(type default)
			)
			(layer "F.SilkS")
		)
		(fp_line
			(start 11.2522 -6.2992)
			(end 11.2522 3.302)
			(stroke
				(width 0.1524)
				(type default)
			)
			(layer "F.SilkS")
		)
		(fp_line
			(start 11.2522 3.302)
			(end -11.2522 3.302)
			(stroke
				(width 0.1524)
				(type default)
			)
			(layer "F.SilkS")
		)
		(fp_poly
			(pts
				(xy -9.273794 -6.315202) (xy -8.841994 -6.747002) (xy -9.705594 -6.747002)
			)
			(stroke
				(width 0)
				(type default)
			)
			(fill yes)
			(layer "F.SilkS")
		)
		(fp_rect
			(start -10.9982 2.8448)
			(end 10.9982 -5.6896)
			(stroke
				(width 0)
				(type default)
			)
			(fill no)
			(layer "F.CrtYd")
		)
		(fp_poly
			(pts
				(xy -11.5062 3.556) (xy -11.5062 -6.5532) (xy 11.5062 -6.5532) (xy 11.5062 -0.00635) (xy 10.9982 -0.00635)
				(xy 10.9982 -5.6896) (xy -10.9982 -5.6896) (xy -10.9982 2.8448) (xy 10.9982 2.8448) (xy 10.9982 0.00635)
				(xy 11.5062 0.00635) (xy 11.5062 3.556)
			)
			(stroke
				(width 0)
				(type default)
			)
			(fill no)
			(layer "F.CrtYd")
		)
		(fp_rect
			(start -11.5062 3.556)
			(end 11.5062 -6.5532)
			(stroke
				(width 0)
				(type default)
			)
			(fill no)
			(layer "F.Fab")
		)
		(pad "" np_thru_hole circle
			(at -9.99998 0)
			(size 0.254 0.254)
			(drill 1.1176)
			(layers "*.Cu" "*.Mask")
			(clearance 0.7874)
			(thermal_gap 0.7874)
		)
		(pad "" np_thru_hole circle
			(at 9.99998 0)
			(size 0.254 0.254)
			(drill 1.6002)
			(layers "*.Cu" "*.Mask")
			(clearance 1.0287)
			(thermal_gap 1.0287)
		)
		(pad "1" smd rect
			(at -9.249918 -5.275072)
			(size 0.3048 1.5494)
			(layers "F.Cu" "F.Mask" "F.Paste")
			(net "M2_1_PRESENT_N_R")
		)
		(pad "2" smd rect
			(at -8.999982 2.275078)
			(size 0.3048 1.5494)
			(layers "F.Cu" "F.Mask" "F.Paste")
			(net "P3V3_M2")
		)
		(pad "3" smd rect
			(at -8.750046 -5.275072)
			(size 0.3048 1.5494)
			(layers "F.Cu" "F.Mask" "F.Paste")
			(net "GND")
		)
		(pad "4" smd rect
			(at -8.50011 2.275078)
			(size 0.3048 1.5494)
			(layers "F.Cu" "F.Mask" "F.Paste")
			(net "P3V3_M2")
		)
		(pad "5" smd rect
			(at -8.24992 -5.275072)
			(size 0.3048 1.5494)
			(layers "F.Cu" "F.Mask" "F.Paste")
			(net "PCIE_IOM_TO_COMP_11_DN")
		)
		(pad "6" smd rect
			(at -7.999984 2.275078)
			(size 0.3048 1.5494)
			(layers "F.Cu" "F.Mask" "F.Paste")
			(net "Net_623")
		)
		(pad "7" smd rect
			(at -7.750048 -5.275072)
			(size 0.3048 1.5494)
			(layers "F.Cu" "F.Mask" "F.Paste")
			(net "PCIE_IOM_TO_COMP_11_DP")
		)
		(pad "8" smd rect
			(at -7.500112 2.275078)
			(size 0.3048 1.5494)
			(layers "F.Cu" "F.Mask" "F.Paste")
			(net "Net_624")
		)
		(pad "9" smd rect
			(at -7.249922 -5.275072)
			(size 0.3048 1.5494)
			(layers "F.Cu" "F.Mask" "F.Paste")
			(net "GND")
		)
		(pad "10" smd rect
			(at -6.999986 2.275078)
			(size 0.3048 1.5494)
			(layers "F.Cu" "F.Mask" "F.Paste")
			(net "M2_1_ACTIVE_N")
		)
		(pad "11" smd rect
			(at -6.75005 -5.275072)
			(size 0.3048 1.5494)
			(layers "F.Cu" "F.Mask" "F.Paste")
			(net "PCIE_COMP_TO_IOM_11_DN")
		)
		(pad "12" smd rect
			(at -6.500114 2.275078)
			(size 0.3048 1.5494)
			(layers "F.Cu" "F.Mask" "F.Paste")
			(net "P3V3_M2")
		)
		(pad "13" smd rect
			(at -6.249924 -5.275072)
			(size 0.3048 1.5494)
			(layers "F.Cu" "F.Mask" "F.Paste")
			(net "PCIE_COMP_TO_IOM_11_DP")
		)
		(pad "14" smd rect
			(at -5.999988 2.275078)
			(size 0.3048 1.5494)
			(layers "F.Cu" "F.Mask" "F.Paste")
			(net "P3V3_M2")
		)
		(pad "15" smd rect
			(at -5.750052 -5.275072)
			(size 0.3048 1.5494)
			(layers "F.Cu" "F.Mask" "F.Paste")
			(net "GND")
		)
		(pad "16" smd rect
			(at -5.500116 2.275078)
			(size 0.3048 1.5494)
			(layers "F.Cu" "F.Mask" "F.Paste")
			(net "P3V3_M2")
		)
		(pad "17" smd rect
			(at -5.249926 -5.275072)
			(size 0.3048 1.5494)
			(layers "F.Cu" "F.Mask" "F.Paste")
			(net "PCIE_IOM_TO_COMP_10_DN")
		)
		(pad "18" smd rect
			(at -4.99999 2.275078)
			(size 0.3048 1.5494)
			(layers "F.Cu" "F.Mask" "F.Paste")
			(net "P3V3_M2")
		)
		(pad "19" smd rect
			(at -4.750054 -5.275072)
			(size 0.3048 1.5494)
			(layers "F.Cu" "F.Mask" "F.Paste")
			(net "PCIE_IOM_TO_COMP_10_DP")
		)
		(pad "20" smd rect
			(at -4.500118 2.275078)
			(size 0.3048 1.5494)
			(layers "F.Cu" "F.Mask" "F.Paste")
			(net "Net_625")
		)
		(pad "21" smd rect
			(at -4.249928 -5.275072)
			(size 0.3048 1.5494)
			(layers "F.Cu" "F.Mask" "F.Paste")
			(net "GND")
		)
		(pad "22" smd rect
			(at -3.999992 2.275078)
			(size 0.3048 1.5494)
			(layers "F.Cu" "F.Mask" "F.Paste")
			(net "Net_626")
		)
		(pad "23" smd rect
			(at -3.750056 -5.275072)
			(size 0.3048 1.5494)
			(layers "F.Cu" "F.Mask" "F.Paste")
			(net "PCIE_COMP_TO_IOM_10_DN")
		)
		(pad "24" smd rect
			(at -3.50012 2.275078)
			(size 0.3048 1.5494)
			(layers "F.Cu" "F.Mask" "F.Paste")
			(net "Net_613")
		)
		(pad "25" smd rect
			(at -3.24993 -5.275072)
			(size 0.3048 1.5494)
			(layers "F.Cu" "F.Mask" "F.Paste")
			(net "PCIE_COMP_TO_IOM_10_DP")
		)
		(pad "26" smd rect
			(at -2.999994 2.275078)
			(size 0.3048 1.5494)
			(layers "F.Cu" "F.Mask" "F.Paste")
			(net "Net_614")
		)
		(pad "27" smd rect
			(at -2.750058 -5.275072)
			(size 0.3048 1.5494)
			(layers "F.Cu" "F.Mask" "F.Paste")
			(net "GND")
		)
		(pad "28" smd rect
			(at -2.500122 2.275078)
			(size 0.3048 1.5494)
			(layers "F.Cu" "F.Mask" "F.Paste")
			(net "Net_615")
		)
		(pad "29" smd rect
			(at -2.249932 -5.275072)
			(size 0.3048 1.5494)
			(layers "F.Cu" "F.Mask" "F.Paste")
			(net "PCIE_IOM_TO_COMP_9_DN")
		)
		(pad "30" smd rect
			(at -1.999996 2.275078)
			(size 0.3048 1.5494)
			(layers "F.Cu" "F.Mask" "F.Paste")
			(net "Net_616")
		)
		(pad "31" smd rect
			(at -1.75006 -5.275072)
			(size 0.3048 1.5494)
			(layers "F.Cu" "F.Mask" "F.Paste")
			(net "PCIE_IOM_TO_COMP_9_DP")
		)
		(pad "32" smd rect
			(at -1.500124 2.275078)
			(size 0.3048 1.5494)
			(layers "F.Cu" "F.Mask" "F.Paste")
			(net "Net_617")
		)
		(pad "33" smd rect
			(at -1.249934 -5.275072)
			(size 0.3048 1.5494)
			(layers "F.Cu" "F.Mask" "F.Paste")
			(net "GND")
		)
		(pad "34" smd rect
			(at -0.999998 2.275078)
			(size 0.3048 1.5494)
			(layers "F.Cu" "F.Mask" "F.Paste")
			(net "Net_618")
		)
		(pad "35" smd rect
			(at -0.750062 -5.275072)
			(size 0.3048 1.5494)
			(layers "F.Cu" "F.Mask" "F.Paste")
			(net "PCIE_COMP_TO_IOM_9_DN")
		)
		(pad "36" smd rect
			(at -0.500126 2.275078)
			(size 0.3048 1.5494)
			(layers "F.Cu" "F.Mask" "F.Paste")
			(net "Net_619")
		)
		(pad "37" smd rect
			(at -0.249936 -5.275072)
			(size 0.3048 1.5494)
			(layers "F.Cu" "F.Mask" "F.Paste")
			(net "PCIE_COMP_TO_IOM_9_DP")
		)
		(pad "38" smd rect
			(at 0 2.275078)
			(size 0.3048 1.5494)
			(layers "F.Cu" "F.Mask" "F.Paste")
			(net "Net_620")
		)
		(pad "39" smd rect
			(at 0.249936 -5.275072)
			(size 0.3048 1.5494)
			(layers "F.Cu" "F.Mask" "F.Paste")
			(net "GND")
		)
		(pad "40" smd rect
			(at 0.500126 2.275078)
			(size 0.3048 1.5494)
			(layers "F.Cu" "F.Mask" "F.Paste")
			(net "I2C_M2_1_1V8_SCL")
		)
		(pad "41" smd rect
			(at 0.750062 -5.275072)
			(size 0.3048 1.5494)
			(layers "F.Cu" "F.Mask" "F.Paste")
			(net "PCIE_IOM_TO_COMP_8_DN")
		)
		(pad "42" smd rect
			(at 0.999998 2.275078)
			(size 0.3048 1.5494)
			(layers "F.Cu" "F.Mask" "F.Paste")
			(net "I2C_M2_1_1V8_SDA")
		)
		(pad "43" smd rect
			(at 1.249934 -5.275072)
			(size 0.3048 1.5494)
			(layers "F.Cu" "F.Mask" "F.Paste")
			(net "PCIE_IOM_TO_COMP_8_DP")
		)
		(pad "44" smd rect
			(at 1.500124 2.275078)
			(size 0.3048 1.5494)
			(layers "F.Cu" "F.Mask" "F.Paste")
			(net "M2_1_ALERT#")
		)
		(pad "45" smd rect
			(at 1.75006 -5.275072)
			(size 0.3048 1.5494)
			(layers "F.Cu" "F.Mask" "F.Paste")
			(net "GND")
		)
		(pad "46" smd rect
			(at 1.999996 2.275078)
			(size 0.3048 1.5494)
			(layers "F.Cu" "F.Mask" "F.Paste")
			(net "Net_621")
		)
		(pad "47" smd rect
			(at 2.249932 -5.275072)
			(size 0.3048 1.5494)
			(layers "F.Cu" "F.Mask" "F.Paste")
			(net "PCIE_COMP_TO_IOM_8_DN")
		)
		(pad "48" smd rect
			(at 2.500122 2.275078)
			(size 0.3048 1.5494)
			(layers "F.Cu" "F.Mask" "F.Paste")
			(net "Net_622")
		)
		(pad "49" smd rect
			(at 2.750058 -5.275072)
			(size 0.3048 1.5494)
			(layers "F.Cu" "F.Mask" "F.Paste")
			(net "PCIE_COMP_TO_IOM_8_DP")
		)
		(pad "50" smd rect
			(at 2.999994 2.275078)
			(size 0.3048 1.5494)
			(layers "F.Cu" "F.Mask" "F.Paste")
			(net "PCIE_COMP_TO_IOM_RST_2")
		)
		(pad "51" smd rect
			(at 3.24993 -5.275072)
			(size 0.3048 1.5494)
			(layers "F.Cu" "F.Mask" "F.Paste")
			(net "GND")
		)
		(pad "52" smd rect
			(at 3.50012 2.275078)
			(size 0.3048 1.5494)
			(layers "F.Cu" "F.Mask" "F.Paste")
			(net "M2_1_CLKREQ#")
		)
		(pad "53" smd rect
			(at 3.750056 -5.275072)
			(size 0.3048 1.5494)
			(layers "F.Cu" "F.Mask" "F.Paste")
			(net "PCIE_COMP_TO_IOM_CLK_2_DN")
		)
		(pad "54" smd rect
			(at 3.999992 2.275078)
			(size 0.3048 1.5494)
			(layers "F.Cu" "F.Mask" "F.Paste")
			(net "Net_610")
		)
		(pad "55" smd rect
			(at 4.249928 -5.275072)
			(size 0.3048 1.5494)
			(layers "F.Cu" "F.Mask" "F.Paste")
			(net "PCIE_COMP_TO_IOM_CLK_2_DP")
		)
		(pad "56" smd rect
			(at 4.500118 2.275078)
			(size 0.3048 1.5494)
			(layers "F.Cu" "F.Mask" "F.Paste")
			(net "TP_M2_1_MFG_DAT")
		)
		(pad "57" smd rect
			(at 4.750054 -5.275072)
			(size 0.3048 1.5494)
			(layers "F.Cu" "F.Mask" "F.Paste")
			(net "GND")
		)
		(pad "58" smd rect
			(at 4.99999 2.275078)
			(size 0.3048 1.5494)
			(layers "F.Cu" "F.Mask" "F.Paste")
			(net "TP_M2_1_MFG_CLK")
		)
		(pad "67" smd rect
			(at 7.249922 -5.275072)
			(size 0.3048 1.5494)
			(layers "F.Cu" "F.Mask" "F.Paste")
			(net "Net_608")
		)
		(pad "68" smd rect
			(at 7.500112 2.275078)
			(size 0.3048 1.5494)
			(layers "F.Cu" "F.Mask" "F.Paste")
			(net "Net_611")
		)
		(pad "69" smd rect
			(at 7.750048 -5.275072)
			(size 0.3048 1.5494)
			(layers "F.Cu" "F.Mask" "F.Paste")
			(net "Net_609")
		)
		(pad "70" smd rect
			(at 7.999984 2.275078)
			(size 0.3048 1.5494)
			(layers "F.Cu" "F.Mask" "F.Paste")
			(net "P3V3_M2")
		)
		(pad "71" smd rect
			(at 8.24992 -5.275072)
			(size 0.3048 1.5494)
			(layers "F.Cu" "F.Mask" "F.Paste")
			(net "GND")
		)
		(pad "72" smd rect
			(at 8.50011 2.275078)
			(size 0.3048 1.5494)
			(layers "F.Cu" "F.Mask" "F.Paste")
			(net "P3V3_M2")
		)
		(pad "73" smd rect
			(at 8.750046 -5.275072)
			(size 0.3048 1.5494)
			(layers "F.Cu" "F.Mask" "F.Paste")
			(net "GND")
		)
		(pad "74" smd rect
			(at 8.999982 2.275078)
			(size 0.3048 1.5494)
			(layers "F.Cu" "F.Mask" "F.Paste")
			(net "P3V3_M2")
		)
		(pad "75" smd rect
			(at 9.249918 -5.275072)
			(size 0.3048 1.5494)
			(layers "F.Cu" "F.Mask" "F.Paste")
			(net "GND")
		)
		(pad "76" smd rect
			(at -10.349992 -4.500118)
			(size 1.1938 2.7432)
			(layers "F.Cu" "F.Mask" "F.Paste")
			(net "GND")
		)
		(pad "77" smd rect
			(at 10.349992 -4.500118)
			(size 1.1938 2.7432)
			(layers "F.Cu" "F.Mask" "F.Paste")
			(net "GND")
		)
		(zone
			(layer "F.Cu")
			(hatch none 0.5)
			(connect_pads
				(clearance 0)
			)
			(min_thickness 0.25)
			(keepout
				(tracks allowed)
				(vias not_allowed)
				(pads allowed)
				(copperpour not_allowed)
				(footprints allowed)
			)
			(placement
				(enabled no)
				(sheetname "")
			)
			(fill
				(thermal_gap 0.5)
				(thermal_bridge_width 0.5)
				(island_removal_mode 0)
			)
			(polygon
				(pts
					(xy 194.997578 -133.592316) (xy 209.30235 -133.592316) (xy 209.30235 -134.100316) (xy 194.997578 -134.100316)
				)
			)
		)
		(zone
			(layer "F.Cu")
			(hatch none 0.5)
			(connect_pads
				(clearance 0)
			)
			(min_thickness 0.25)
			(keepout
				(tracks allowed)
				(vias not_allowed)
				(pads allowed)
				(copperpour not_allowed)
				(footprints allowed)
			)
			(placement
				(enabled no)
				(sheetname "")
			)
			(fill
				(thermal_gap 0.5)
				(thermal_bridge_width 0.5)
				(island_removal_mode 0)
			)
			(polygon
				(pts
					(xy 195.247514 -128.099566) (xy 209.552286 -128.099566) (xy 209.552286 -128.607566) (xy 195.247514 -128.607566)
				)
			)
		)
		(zone
			(layer "F.Cu")
			(hatch none 0.5)
			(connect_pads
				(clearance 0)
			)
			(min_thickness 0.25)
			(keepout
				(tracks allowed)
				(vias not_allowed)
				(pads allowed)
				(copperpour not_allowed)
				(footprints allowed)
			)
			(placement
				(enabled no)
				(sheetname "")
			)
			(fill
				(thermal_gap 0.5)
				(thermal_bridge_width 0.5)
				(island_removal_mode 0)
			)
			(polygon
				(pts
					(xy 211.497418 -133.592316) (xy 213.802214 -133.592316) (xy 213.802214 -134.100316) (xy 211.497418 -134.100316)
				)
			)
		)
		(zone
			(layer "F.Cu")
			(hatch none 0.5)
			(connect_pads
				(clearance 0)
			)
			(min_thickness 0.25)
			(keepout
				(tracks allowed)
				(vias not_allowed)
				(pads allowed)
				(copperpour not_allowed)
				(footprints allowed)
			)
			(placement
				(enabled no)
				(sheetname "")
			)
			(fill
				(thermal_gap 0.5)
				(thermal_bridge_width 0.5)
				(island_removal_mode 0)
			)
			(polygon
				(pts
					(xy 211.747608 -128.099566) (xy 213.552278 -128.099566) (xy 213.552278 -128.607566) (xy 211.747608 -128.607566)
				)
			)
		)
		(zone
			(layers "F.Cu" "B.Cu" "In1.Cu" "In2.Cu" "In3.Cu" "In4.Cu" "In5.Cu" "In6.Cu")
			(hatch none 0.5)
			(connect_pads
				(clearance 0)
			)
			(min_thickness 0.25)
			(keepout
				(tracks not_allowed)
				(vias allowed)
				(pads allowed)
				(copperpour not_allowed)
				(footprints allowed)
			)
			(placement
				(enabled no)
				(sheetname "")
			)
			(fill
				(thermal_gap 0.5)
				(thermal_bridge_width 0.5)
				(island_removal_mode 0)
			)
			(polygon
				(pts
					(arc
						(start 195.263516 -129.599944)
						(mid 193.536316 -129.599944)
						(end 195.263516 -129.599944)
					)
				)
			)
		)
		(zone
			(layers "F.Cu" "B.Cu" "In1.Cu" "In2.Cu" "In3.Cu" "In4.Cu" "In5.Cu" "In6.Cu")
			(hatch none 0.5)
			(connect_pads
				(clearance 0)
			)
			(min_thickness 0.25)
			(keepout
				(tracks not_allowed)
				(vias allowed)
				(pads allowed)
				(copperpour not_allowed)
				(footprints allowed)
			)
			(placement
				(enabled no)
				(sheetname "")
			)
			(fill
				(thermal_gap 0.5)
				(thermal_bridge_width 0.5)
				(island_removal_mode 0)
			)
			(polygon
				(pts
					(arc
						(start 215.504776 -129.599944)
						(mid 213.294976 -129.599944)
						(end 215.504776 -129.599944)
					)
				)
			)
		)
	)
)
